(kicad_pcb
	(version 20260206)
	(generator "pcbnew")
	(generator_version "10.0")
	(general
		(thickness 1.6)
		(legacy_teardrops no)
	)
	(paper "A4")
	(title_block
		(title "03242023_DA0F0TMBIJ0_F0T_Motherboard_J_brd_V01_OCP.brd")
		(comment 1 "Grand Teton / footprints 3920-3925 of 6105")
	)
	(layers
		(0 "F.Cu" signal "TOP")
		(4 "In1.Cu" signal "GND")
		(6 "In2.Cu" signal "IN1")
		(8 "In3.Cu" signal "GND1")
		(10 "In4.Cu" signal "IN2")
		(12 "In5.Cu" signal "GND2")
		(14 "In6.Cu" signal "IN3")
		(16 "In7.Cu" signal "GND3")
		(18 "In8.Cu" signal "VCC")
		(20 "In9.Cu" signal "VCC1")
		(22 "In10.Cu" signal "GND4")
		(24 "In11.Cu" signal "IN4")
		(26 "In12.Cu" signal "GND5")
		(28 "In13.Cu" signal "IN5")
		(30 "In14.Cu" signal "GND6")
		(32 "In15.Cu" signal "IN6")
		(34 "In16.Cu" signal "GND7")
		(2 "B.Cu" signal "BOTTOM")
		(9 "F.Adhes" user "F.Adhesive")
		(11 "B.Adhes" user "B.Adhesive")
		(13 "F.Paste" user "Package Geometry/Pastemask Top")
		(15 "B.Paste" user "Package Geometry/Pastemask Bottom")
		(5 "F.SilkS" user "Ref Des/Silkscreen Top")
		(7 "B.SilkS" user "Ref Des/Silkscreen Bottom")
		(1 "F.Mask" user "Board Geometry/Soldermask Top")
		(3 "B.Mask" user "Board Geometry/Soldermask Bottom")
		(17 "Dwgs.User" user "User.Drawings")
		(19 "Cmts.User" user "User.Comments")
		(21 "Eco1.User" user "User.Eco1")
		(23 "Eco2.User" user "User.Eco2")
		(25 "Edge.Cuts" user "Board Geometry/Outline")
		(27 "Margin" user)
		(31 "F.CrtYd" user "Package Geometry/Place Bound Top")
		(29 "B.CrtYd" user "Package Geometry/Place Bound Bottom")
		(35 "F.Fab" user "Ref Des/Assembly Top")
		(33 "B.Fab" user "Ref Des/Assembly Bottom")
	)
	(footprint ""
		(layer "F.Cu")
		(at 113.494312 -137.799826 180)
		(property "Reference" "R539"
			(at 0 0 180)
			(layer "F.SilkS")
			(hide yes)
			(effects
				(font
					(size 1.27 1.27)
				)
			)
		)
		(property "Value" ""
			(at 0 0 180)
			(layer "F.Fab")
			(effects
				(font
					(size 1.27 1.27)
				)
			)
		)
		(duplicate_pad_numbers_are_jumpers no)
		(fp_line
			(start 0.7874 0.4064)
			(end -0.7874 0.4064)
			(stroke
				(width 0.1524)
				(type default)
			)
			(layer "F.SilkS")
		)
		(fp_line
			(start 0.7874 -0.4064)
			(end 0.7874 0.4064)
			(stroke
				(width 0.1524)
				(type default)
			)
			(layer "F.SilkS")
		)
		(fp_line
			(start -0.7874 0.4064)
			(end -0.7874 -0.4064)
			(stroke
				(width 0.1524)
				(type default)
			)
			(layer "F.SilkS")
		)
		(fp_line
			(start -0.7874 -0.4064)
			(end 0.7874 -0.4064)
			(stroke
				(width 0.1524)
				(type default)
			)
			(layer "F.SilkS")
		)
		(fp_line
			(start 0.67945 0.3048)
			(end 0.120396 0.3048)
			(stroke
				(width 0.1)
				(type default)
			)
			(layer "F.Fab")
		)
		(fp_line
			(start 0.67945 -0.3048)
			(end 0.67945 0.3048)
			(stroke
				(width 0.1)
				(type default)
			)
			(layer "F.Fab")
		)
		(fp_line
			(start 0.12065 -0.2794)
			(end 0.12065 -0.3048)
			(stroke
				(width 0.1)
				(type default)
			)
			(layer "F.Fab")
		)
		(fp_line
			(start 0.12065 -0.3048)
			(end 0.67945 -0.3048)
			(stroke
				(width 0.1)
				(type default)
			)
			(layer "F.Fab")
		)
		(fp_line
			(start 0.120396 0.3048)
			(end 0.120396 0.2794)
			(stroke
				(width 0.1)
				(type default)
			)
			(layer "F.Fab")
		)
		(fp_line
			(start 0.120396 0.2794)
			(end -0.12065 0.2794)
			(stroke
				(width 0.1)
				(type default)
			)
			(layer "F.Fab")
		)
		(fp_line
			(start -0.12065 0.3048)
			(end -0.67945 0.3048)
			(stroke
				(width 0.1)
				(type default)
			)
			(layer "F.Fab")
		)
		(fp_line
			(start -0.12065 0.2794)
			(end -0.12065 0.3048)
			(stroke
				(width 0.1)
				(type default)
			)
			(layer "F.Fab")
		)
		(fp_line
			(start -0.12065 -0.2794)
			(end 0.12065 -0.2794)
			(stroke
				(width 0.1)
				(type default)
			)
			(layer "F.Fab")
		)
		(fp_line
			(start -0.12065 -0.305054)
			(end -0.12065 -0.2794)
			(stroke
				(width 0.1)
				(type default)
			)
			(layer "F.Fab")
		)
		(fp_line
			(start -0.67945 0.3048)
			(end -0.67945 -0.305054)
			(stroke
				(width 0.1)
				(type default)
			)
			(layer "F.Fab")
		)
		(fp_line
			(start -0.67945 -0.305054)
			(end -0.12065 -0.305054)
			(stroke
				(width 0.1)
				(type default)
			)
			(layer "F.Fab")
		)
		(pad "1" smd circle
			(at -0.40005 0 180)
			(size 0 0)
			(layers "F.Cu" "F.Mask" "F.Paste")
			(net "PCA9548_PCIE3_ADDR1")
		)
		(pad "2" smd circle
			(at 0.40005 0 180)
			(size 0 0)
			(layers "F.Cu" "F.Mask" "F.Paste")
			(net "GND")
		)
	)
	(footprint ""
		(layer "F.Cu")
		(at 363.22 -415.889948 180)
		(property "Reference" "R4560"
			(at 0 0 180)
			(layer "F.SilkS")
			(hide yes)
			(effects
				(font
					(size 1.27 1.27)
				)
			)
		)
		(property "Value" ""
			(at 0 0 180)
			(layer "F.Fab")
			(effects
				(font
					(size 1.27 1.27)
				)
			)
		)
		(duplicate_pad_numbers_are_jumpers no)
		(fp_line
			(start 0.7874 0.4064)
			(end -0.7874 0.4064)
			(stroke
				(width 0.1524)
				(type default)
			)
			(layer "F.SilkS")
		)
		(fp_line
			(start 0.7874 -0.4064)
			(end 0.7874 0.4064)
			(stroke
				(width 0.1524)
				(type default)
			)
			(layer "F.SilkS")
		)
		(fp_line
			(start -0.7874 0.4064)
			(end -0.7874 -0.4064)
			(stroke
				(width 0.1524)
				(type default)
			)
			(layer "F.SilkS")
		)
		(fp_line
			(start -0.7874 -0.4064)
			(end 0.7874 -0.4064)
			(stroke
				(width 0.1524)
				(type default)
			)
			(layer "F.SilkS")
		)
		(fp_line
			(start 0.67945 0.3048)
			(end 0.120396 0.3048)
			(stroke
				(width 0.1)
				(type default)
			)
			(layer "F.Fab")
		)
		(fp_line
			(start 0.67945 -0.3048)
			(end 0.67945 0.3048)
			(stroke
				(width 0.1)
				(type default)
			)
			(layer "F.Fab")
		)
		(fp_line
			(start 0.12065 -0.2794)
			(end 0.12065 -0.3048)
			(stroke
				(width 0.1)
				(type default)
			)
			(layer "F.Fab")
		)
		(fp_line
			(start 0.12065 -0.3048)
			(end 0.67945 -0.3048)
			(stroke
				(width 0.1)
				(type default)
			)
			(layer "F.Fab")
		)
		(fp_line
			(start 0.120396 0.3048)
			(end 0.120396 0.2794)
			(stroke
				(width 0.1)
				(type default)
			)
			(layer "F.Fab")
		)
		(fp_line
			(start 0.120396 0.2794)
			(end -0.12065 0.2794)
			(stroke
				(width 0.1)
				(type default)
			)
			(layer "F.Fab")
		)
		(fp_line
			(start -0.12065 0.3048)
			(end -0.67945 0.3048)
			(stroke
				(width 0.1)
				(type default)
			)
			(layer "F.Fab")
		)
		(fp_line
			(start -0.12065 0.2794)
			(end -0.12065 0.3048)
			(stroke
				(width 0.1)
				(type default)
			)
			(layer "F.Fab")
		)
		(fp_line
			(start -0.12065 -0.2794)
			(end 0.12065 -0.2794)
			(stroke
				(width 0.1)
				(type default)
			)
			(layer "F.Fab")
		)
		(fp_line
			(start -0.12065 -0.305054)
			(end -0.12065 -0.2794)
			(stroke
				(width 0.1)
				(type default)
			)
			(layer "F.Fab")
		)
		(fp_line
			(start -0.67945 0.3048)
			(end -0.67945 -0.305054)
			(stroke
				(width 0.1)
				(type default)
			)
			(layer "F.Fab")
		)
		(fp_line
			(start -0.67945 -0.305054)
			(end -0.12065 -0.305054)
			(stroke
				(width 0.1)
				(type default)
			)
			(layer "F.Fab")
		)
		(pad "1" smd circle
			(at -0.40005 0 180)
			(size 0 0)
			(layers "F.Cu" "F.Mask" "F.Paste")
			(net "P3V3_AUX")
		)
		(pad "2" smd circle
			(at 0.40005 0 180)
			(size 0 0)
			(layers "F.Cu" "F.Mask" "F.Paste")
			(net "SWB_HSC_PWRGD_N")
		)
	)
	(footprint ""
		(layer "F.Cu")
		(at 445.090296 -51.305968 -90)
		(property "Reference" "C1332"
			(at 0 0 270)
			(layer "F.SilkS")
			(hide yes)
			(effects
				(font
					(size 1.27 1.27)
				)
			)
		)
		(property "Value" ""
			(at 0 0 270)
			(layer "F.Fab")
			(effects
				(font
					(size 1.27 1.27)
				)
			)
		)
		(duplicate_pad_numbers_are_jumpers no)
		(fp_line
			(start -0.7874 0.4064)
			(end -0.7874 -0.4064)
			(stroke
				(width 0.1524)
				(type default)
			)
			(layer "F.SilkS")
		)
		(fp_line
			(start 0.7874 0.4064)
			(end -0.7874 0.4064)
			(stroke
				(width 0.1524)
				(type default)
			)
			(layer "F.SilkS")
		)
		(fp_line
			(start -0.7874 -0.4064)
			(end 0.7874 -0.4064)
			(stroke
				(width 0.1524)
				(type default)
			)
			(layer "F.SilkS")
		)
		(fp_line
			(start 0.7874 -0.4064)
			(end 0.7874 0.4064)
			(stroke
				(width 0.1524)
				(type default)
			)
			(layer "F.SilkS")
		)
		(fp_line
			(start -0.67945 0.3048)
			(end -0.67945 -0.305054)
			(stroke
				(width 0.1)
				(type default)
			)
			(layer "F.Fab")
		)
		(fp_line
			(start -0.12065 0.3048)
			(end -0.67945 0.3048)
			(stroke
				(width 0.1)
				(type default)
			)
			(layer "F.Fab")
		)
		(fp_line
			(start 0.120396 0.3048)
			(end 0.120396 0.2794)
			(stroke
				(width 0.1)
				(type default)
			)
			(layer "F.Fab")
		)
		(fp_line
			(start 0.67945 0.3048)
			(end 0.120396 0.3048)
			(stroke
				(width 0.1)
				(type default)
			)
			(layer "F.Fab")
		)
		(fp_line
			(start -0.12065 0.2794)
			(end -0.12065 0.3048)
			(stroke
				(width 0.1)
				(type default)
			)
			(layer "F.Fab")
		)
		(fp_line
			(start 0.120396 0.2794)
			(end -0.12065 0.2794)
			(stroke
				(width 0.1)
				(type default)
			)
			(layer "F.Fab")
		)
		(fp_line
			(start -0.12065 -0.2794)
			(end 0.12065 -0.2794)
			(stroke
				(width 0.1)
				(type default)
			)
			(layer "F.Fab")
		)
		(fp_line
			(start 0.12065 -0.2794)
			(end 0.12065 -0.3048)
			(stroke
				(width 0.1)
				(type default)
			)
			(layer "F.Fab")
		)
		(fp_line
			(start 0.12065 -0.3048)
			(end 0.67945 -0.3048)
			(stroke
				(width 0.1)
				(type default)
			)
			(layer "F.Fab")
		)
		(fp_line
			(start 0.67945 -0.3048)
			(end 0.67945 0.3048)
			(stroke
				(width 0.1)
				(type default)
			)
			(layer "F.Fab")
		)
		(fp_line
			(start -0.67945 -0.305054)
			(end -0.12065 -0.305054)
			(stroke
				(width 0.1)
				(type default)
			)
			(layer "F.Fab")
		)
		(fp_line
			(start -0.12065 -0.305054)
			(end -0.12065 -0.2794)
			(stroke
				(width 0.1)
				(type default)
			)
			(layer "F.Fab")
		)
		(pad "1" smd circle
			(at -0.40005 0 270)
			(size 0 0)
			(layers "F.Cu" "F.Mask" "F.Paste")
			(net "P3V3_AUX")
		)
		(pad "2" smd circle
			(at 0.40005 0 270)
			(size 0 0)
			(layers "F.Cu" "F.Mask" "F.Paste")
			(net "GND")
		)
	)
	(footprint ""
		(layer "F.Cu")
		(at 134.2136 -125.758448)
		(property "Reference" "R3151"
			(at 0 0 0)
			(layer "F.SilkS")
			(hide yes)
			(effects
				(font
					(size 1.27 1.27)
				)
			)
		)
		(property "Value" ""
			(at 0 0 0)
			(layer "F.Fab")
			(effects
				(font
					(size 1.27 1.27)
				)
			)
		)
		(duplicate_pad_numbers_are_jumpers no)
		(fp_line
			(start -0.7874 -0.4064)
			(end 0.7874 -0.4064)
			(stroke
				(width 0.1524)
				(type default)
			)
			(layer "F.SilkS")
		)
		(fp_line
			(start -0.7874 0.4064)
			(end -0.7874 -0.4064)
			(stroke
				(width 0.1524)
				(type default)
			)
			(layer "F.SilkS")
		)
		(fp_line
			(start 0.7874 -0.4064)
			(end 0.7874 0.4064)
			(stroke
				(width 0.1524)
				(type default)
			)
			(layer "F.SilkS")
		)
		(fp_line
			(start 0.7874 0.4064)
			(end -0.7874 0.4064)
			(stroke
				(width 0.1524)
				(type default)
			)
			(layer "F.SilkS")
		)
		(fp_line
			(start -0.67945 -0.305054)
			(end -0.12065 -0.305054)
			(stroke
				(width 0.1)
				(type default)
			)
			(layer "F.Fab")
		)
		(fp_line
			(start -0.67945 0.3048)
			(end -0.67945 -0.305054)
			(stroke
				(width 0.1)
				(type default)
			)
			(layer "F.Fab")
		)
		(fp_line
			(start -0.12065 -0.305054)
			(end -0.12065 -0.2794)
			(stroke
				(width 0.1)
				(type default)
			)
			(layer "F.Fab")
		)
		(fp_line
			(start -0.12065 -0.2794)
			(end 0.12065 -0.2794)
			(stroke
				(width 0.1)
				(type default)
			)
			(layer "F.Fab")
		)
		(fp_line
			(start -0.12065 0.2794)
			(end -0.12065 0.3048)
			(stroke
				(width 0.1)
				(type default)
			)
			(layer "F.Fab")
		)
		(fp_line
			(start -0.12065 0.3048)
			(end -0.67945 0.3048)
			(stroke
				(width 0.1)
				(type default)
			)
			(layer "F.Fab")
		)
		(fp_line
			(start 0.120396 0.2794)
			(end -0.12065 0.2794)
			(stroke
				(width 0.1)
				(type default)
			)
			(layer "F.Fab")
		)
		(fp_line
			(start 0.120396 0.3048)
			(end 0.120396 0.2794)
			(stroke
				(width 0.1)
				(type default)
			)
			(layer "F.Fab")
		)
		(fp_line
			(start 0.12065 -0.3048)
			(end 0.67945 -0.3048)
			(stroke
				(width 0.1)
				(type default)
			)
			(layer "F.Fab")
		)
		(fp_line
			(start 0.12065 -0.2794)
			(end 0.12065 -0.3048)
			(stroke
				(width 0.1)
				(type default)
			)
			(layer "F.Fab")
		)
		(fp_line
			(start 0.67945 -0.3048)
			(end 0.67945 0.3048)
			(stroke
				(width 0.1)
				(type default)
			)
			(layer "F.Fab")
		)
		(fp_line
			(start 0.67945 0.3048)
			(end 0.120396 0.3048)
			(stroke
				(width 0.1)
				(type default)
			)
			(layer "F.Fab")
		)
		(pad "1" smd circle
			(at -0.40005 0)
			(size 0 0)
			(layers "F.Cu" "F.Mask" "F.Paste")
			(net "P3V3_AUX")
		)
		(pad "2" smd circle
			(at 0.40005 0)
			(size 0 0)
			(layers "F.Cu" "F.Mask" "F.Paste")
			(net "PD_SMB_OCP2_HP_ADD1")
		)
	)
	(footprint ""
		(layer "F.Cu")
		(at 266.032234 -94.192598 90)
		(property "Reference" "C172"
			(at 0 0 90)
			(layer "F.SilkS")
			(hide yes)
			(effects
				(font
					(size 1.27 1.27)
				)
			)
		)
		(property "Value" ""
			(at 0 0 90)
			(layer "F.Fab")
			(effects
				(font
					(size 1.27 1.27)
				)
			)
		)
		(duplicate_pad_numbers_are_jumpers no)
		(fp_line
			(start 1.2954 -0.5842)
			(end 1.2954 0.5842)
			(stroke
				(width 0.1524)
				(type default)
			)
			(layer "F.SilkS")
		)
		(fp_line
			(start 0 -0.5842)
			(end 0 0.5842)
			(stroke
				(width 0.1524)
				(type default)
			)
			(layer "F.SilkS")
		)
		(fp_line
			(start -1.2954 -0.5842)
			(end 1.2954 -0.5842)
			(stroke
				(width 0.1524)
				(type default)
			)
			(layer "F.SilkS")
		)
		(fp_line
			(start 1.2954 0.5842)
			(end -1.2954 0.5842)
			(stroke
				(width 0.1524)
				(type default)
			)
			(layer "F.SilkS")
		)
		(fp_line
			(start -1.2954 0.5842)
			(end -1.2954 -0.5842)
			(stroke
				(width 0.1524)
				(type default)
			)
			(layer "F.SilkS")
		)
		(fp_line
			(start 0.8636 -0.4572)
			(end 0.8636 -0.4064)
			(stroke
				(width 0.1)
				(type default)
			)
			(layer "F.Fab")
		)
		(fp_line
			(start -0.8636 -0.4572)
			(end 0.8636 -0.4572)
			(stroke
				(width 0.1)
				(type default)
			)
			(layer "F.Fab")
		)
		(fp_line
			(start 1.1938 -0.4064)
			(end 1.1938 0.4064)
			(stroke
				(width 0.1)
				(type default)
			)
			(layer "F.Fab")
		)
		(fp_line
			(start 0.8636 -0.4064)
			(end 1.1938 -0.4064)
			(stroke
				(width 0.1)
				(type default)
			)
			(layer "F.Fab")
		)
		(fp_line
			(start -0.8636 -0.4064)
			(end -0.8636 -0.4572)
			(stroke
				(width 0.1)
				(type default)
			)
			(layer "F.Fab")
		)
		(fp_line
			(start -1.1938 -0.4064)
			(end -0.8636 -0.4064)
			(stroke
				(width 0.1)
				(type default)
			)
			(layer "F.Fab")
		)
		(fp_line
			(start 1.1938 0.4064)
			(end 0.8636 0.4064)
			(stroke
				(width 0.1)
				(type default)
			)
			(layer "F.Fab")
		)
		(fp_line
			(start 0.8636 0.4064)
			(end 0.8636 0.4572)
			(stroke
				(width 0.1)
				(type default)
			)
			(layer "F.Fab")
		)
		(fp_line
			(start -0.8636 0.4064)
			(end -1.1938 0.4064)
			(stroke
				(width 0.1)
				(type default)
			)
			(layer "F.Fab")
		)
		(fp_line
			(start -1.1938 0.4064)
			(end -1.1938 -0.4064)
			(stroke
				(width 0.1)
				(type default)
			)
			(layer "F.Fab")
		)
		(fp_line
			(start 0.8636 0.4572)
			(end -0.8636 0.4572)
			(stroke
				(width 0.1)
				(type default)
			)
			(layer "F.Fab")
		)
		(fp_line
			(start -0.8636 0.4572)
			(end -0.8636 0.4064)
			(stroke
				(width 0.1)
				(type default)
			)
			(layer "F.Fab")
		)
		(pad "1" smd rect
			(at -0.7366 0)
			(size 0.7112 0.8128)
			(layers "F.Cu" "F.Mask" "F.Paste")
			(net "P3V3_AUX_CLK_GEN_VDDA100M_CK440")
		)
		(pad "2" smd rect
			(at 0.7366 0)
			(size 0.7112 0.8128)
			(layers "F.Cu" "F.Mask" "F.Paste")
			(net "GND")
		)
	)
	(footprint ""
		(layer "F.Cu")
		(at 298.66082 -421.41521 90)
		(property "Reference" "R4141"
			(at 0 0 90)
			(layer "F.SilkS")
			(hide yes)
			(effects
				(font
					(size 1.27 1.27)
				)
			)
		)
		(property "Value" ""
			(at 0 0 90)
			(layer "F.Fab")
			(effects
				(font
					(size 1.27 1.27)
				)
			)
		)
		(duplicate_pad_numbers_are_jumpers no)
		(fp_line
			(start 0.7874 -0.4064)
			(end 0.7874 0.4064)
			(stroke
				(width 0.1524)
				(type default)
			)
			(layer "F.SilkS")
		)
		(fp_line
			(start -0.7874 -0.4064)
			(end 0.7874 -0.4064)
			(stroke
				(width 0.1524)
				(type default)
			)
			(layer "F.SilkS")
		)
		(fp_line
			(start 0.7874 0.4064)
			(end -0.7874 0.4064)
			(stroke
				(width 0.1524)
				(type default)
			)
			(layer "F.SilkS")
		)
		(fp_line
			(start -0.7874 0.4064)
			(end -0.7874 -0.4064)
			(stroke
				(width 0.1524)
				(type default)
			)
			(layer "F.SilkS")
		)
		(fp_line
			(start -0.12065 -0.305054)
			(end -0.12065 -0.2794)
			(stroke
				(width 0.1)
				(type default)
			)
			(layer "F.Fab")
		)
		(fp_line
			(start -0.67945 -0.305054)
			(end -0.12065 -0.305054)
			(stroke
				(width 0.1)
				(type default)
			)
			(layer "F.Fab")
		)
		(fp_line
			(start 0.67945 -0.3048)
			(end 0.67945 0.3048)
			(stroke
				(width 0.1)
				(type default)
			)
			(layer "F.Fab")
		)
		(fp_line
			(start 0.12065 -0.3048)
			(end 0.67945 -0.3048)
			(stroke
				(width 0.1)
				(type default)
			)
			(layer "F.Fab")
		)
		(fp_line
			(start 0.12065 -0.2794)
			(end 0.12065 -0.3048)
			(stroke
				(width 0.1)
				(type default)
			)
			(layer "F.Fab")
		)
		(fp_line
			(start -0.12065 -0.2794)
			(end 0.12065 -0.2794)
			(stroke
				(width 0.1)
				(type default)
			)
			(layer "F.Fab")
		)
		(fp_line
			(start 0.120396 0.2794)
			(end -0.12065 0.2794)
			(stroke
				(width 0.1)
				(type default)
			)
			(layer "F.Fab")
		)
		(fp_line
			(start -0.12065 0.2794)
			(end -0.12065 0.3048)
			(stroke
				(width 0.1)
				(type default)
			)
			(layer "F.Fab")
		)
		(fp_line
			(start 0.67945 0.3048)
			(end 0.120396 0.3048)
			(stroke
				(width 0.1)
				(type default)
			)
			(layer "F.Fab")
		)
		(fp_line
			(start 0.120396 0.3048)
			(end 0.120396 0.2794)
			(stroke
				(width 0.1)
				(type default)
			)
			(layer "F.Fab")
		)
		(fp_line
			(start -0.12065 0.3048)
			(end -0.67945 0.3048)
			(stroke
				(width 0.1)
				(type default)
			)
			(layer "F.Fab")
		)
		(fp_line
			(start -0.67945 0.3048)
			(end -0.67945 -0.305054)
			(stroke
				(width 0.1)
				(type default)
			)
			(layer "F.Fab")
		)
		(pad "1" smd circle
			(at -0.40005 0 90)
			(size 0 0)
			(layers "F.Cu" "F.Mask" "F.Paste")
			(net "P3V3_AUX")
		)
		(pad "2" smd circle
			(at 0.40005 0 90)
			(size 0 0)
			(layers "F.Cu" "F.Mask" "F.Paste")
			(net "GPU_3V3IO_RSVD5_FFU_ISO")
		)
	)
)
